(kicad_pcb
	(version 20260206)
	(generator "pcbnew")
	(generator_version "10.0")
	(general
		(thickness 1.6)
		(legacy_teardrops no)
	)
	(paper "A4")
	(title_block
		(title "03242023_DA0F0TMBIJ0_F0T_Motherboard_J_brd_V01_OCP.brd")
		(comment 1 "Grand Teton / footprints 5912-5917 of 6105")
	)
	(layers
		(0 "F.Cu" signal "TOP")
		(4 "In1.Cu" signal "GND")
		(6 "In2.Cu" signal "IN1")
		(8 "In3.Cu" signal "GND1")
		(10 "In4.Cu" signal "IN2")
		(12 "In5.Cu" signal "GND2")
		(14 "In6.Cu" signal "IN3")
		(16 "In7.Cu" signal "GND3")
		(18 "In8.Cu" signal "VCC")
		(20 "In9.Cu" signal "VCC1")
		(22 "In10.Cu" signal "GND4")
		(24 "In11.Cu" signal "IN4")
		(26 "In12.Cu" signal "GND5")
		(28 "In13.Cu" signal "IN5")
		(30 "In14.Cu" signal "GND6")
		(32 "In15.Cu" signal "IN6")
		(34 "In16.Cu" signal "GND7")
		(2 "B.Cu" signal "BOTTOM")
		(9 "F.Adhes" user "F.Adhesive")
		(11 "B.Adhes" user "B.Adhesive")
		(13 "F.Paste" user "Package Geometry/Pastemask Top")
		(15 "B.Paste" user "Package Geometry/Pastemask Bottom")
		(5 "F.SilkS" user "Ref Des/Silkscreen Top")
		(7 "B.SilkS" user "Ref Des/Silkscreen Bottom")
		(1 "F.Mask" user "Board Geometry/Soldermask Top")
		(3 "B.Mask" user "Board Geometry/Soldermask Bottom")
		(17 "Dwgs.User" user "User.Drawings")
		(19 "Cmts.User" user "User.Comments")
		(21 "Eco1.User" user "User.Eco1")
		(23 "Eco2.User" user "User.Eco2")
		(25 "Edge.Cuts" user "Board Geometry/Outline")
		(27 "Margin" user)
		(31 "F.CrtYd" user "Package Geometry/Place Bound Top")
		(29 "B.CrtYd" user "Package Geometry/Place Bound Bottom")
		(35 "F.Fab" user "Ref Des/Assembly Top")
		(33 "B.Fab" user "Ref Des/Assembly Bottom")
	)
	(footprint ""
		(layer "B.Cu")
		(at 396.72006 -50.864008 90)
		(property "Reference" "C551"
			(at 0 0 90)
			(layer "B.SilkS")
			(hide yes)
			(effects
				(font
					(size 1.27 1.27)
				)
				(justify mirror)
			)
		)
		(property "Value" ""
			(at 0 0 90)
			(layer "B.Fab")
			(effects
				(font
					(size 1.27 1.27)
				)
				(justify mirror)
			)
		)
		(duplicate_pad_numbers_are_jumpers no)
		(fp_line
			(start 0.7874 -0.4064)
			(end -0.7874 -0.4064)
			(stroke
				(width 0.1524)
				(type default)
			)
			(layer "B.SilkS")
		)
		(fp_line
			(start -0.7874 -0.4064)
			(end -0.7874 0.4064)
			(stroke
				(width 0.1524)
				(type default)
			)
			(layer "B.SilkS")
		)
		(fp_line
			(start 0.7874 0.4064)
			(end 0.7874 -0.4064)
			(stroke
				(width 0.1524)
				(type default)
			)
			(layer "B.SilkS")
		)
		(fp_line
			(start -0.7874 0.4064)
			(end 0.7874 0.4064)
			(stroke
				(width 0.1524)
				(type default)
			)
			(layer "B.SilkS")
		)
		(fp_line
			(start 0.67945 -0.305054)
			(end 0.12065 -0.305054)
			(stroke
				(width 0.1)
				(type default)
			)
			(layer "B.Fab")
		)
		(fp_line
			(start 0.12065 -0.305054)
			(end 0.12065 -0.2794)
			(stroke
				(width 0.1)
				(type default)
			)
			(layer "B.Fab")
		)
		(fp_line
			(start -0.12065 -0.3048)
			(end -0.67945 -0.3048)
			(stroke
				(width 0.1)
				(type default)
			)
			(layer "B.Fab")
		)
		(fp_line
			(start -0.67945 -0.3048)
			(end -0.67945 0.3048)
			(stroke
				(width 0.1)
				(type default)
			)
			(layer "B.Fab")
		)
		(fp_line
			(start 0.12065 -0.2794)
			(end -0.12065 -0.2794)
			(stroke
				(width 0.1)
				(type default)
			)
			(layer "B.Fab")
		)
		(fp_line
			(start -0.12065 -0.2794)
			(end -0.12065 -0.3048)
			(stroke
				(width 0.1)
				(type default)
			)
			(layer "B.Fab")
		)
		(fp_line
			(start 0.12065 0.2794)
			(end 0.12065 0.3048)
			(stroke
				(width 0.1)
				(type default)
			)
			(layer "B.Fab")
		)
		(fp_line
			(start -0.120396 0.2794)
			(end 0.12065 0.2794)
			(stroke
				(width 0.1)
				(type default)
			)
			(layer "B.Fab")
		)
		(fp_line
			(start 0.67945 0.3048)
			(end 0.67945 -0.305054)
			(stroke
				(width 0.1)
				(type default)
			)
			(layer "B.Fab")
		)
		(fp_line
			(start 0.12065 0.3048)
			(end 0.67945 0.3048)
			(stroke
				(width 0.1)
				(type default)
			)
			(layer "B.Fab")
		)
		(fp_line
			(start -0.120396 0.3048)
			(end -0.120396 0.2794)
			(stroke
				(width 0.1)
				(type default)
			)
			(layer "B.Fab")
		)
		(fp_line
			(start -0.67945 0.3048)
			(end -0.120396 0.3048)
			(stroke
				(width 0.1)
				(type default)
			)
			(layer "B.Fab")
		)
		(pad "1" smd circle
			(at 0.40005 0 270)
			(size 0 0)
			(layers "B.Cu" "B.Mask" "B.Paste")
			(net "P3V3_AUX")
		)
		(pad "2" smd circle
			(at -0.40005 0 270)
			(size 0 0)
			(layers "B.Cu" "B.Mask" "B.Paste")
			(net "GND")
		)
	)
	(footprint ""
		(layer "B.Cu")
		(at 305.589432 -149.533356)
		(property "Reference" "R678"
			(at 0 0 0)
			(layer "B.SilkS")
			(hide yes)
			(effects
				(font
					(size 1.27 1.27)
				)
				(justify mirror)
			)
		)
		(property "Value" ""
			(at 0 0 0)
			(layer "B.Fab")
			(effects
				(font
					(size 1.27 1.27)
				)
				(justify mirror)
			)
		)
		(duplicate_pad_numbers_are_jumpers no)
		(fp_line
			(start -0.7874 -0.4064)
			(end -0.7874 0.4064)
			(stroke
				(width 0.1524)
				(type default)
			)
			(layer "B.SilkS")
		)
		(fp_line
			(start -0.7874 0.4064)
			(end 0.7874 0.4064)
			(stroke
				(width 0.1524)
				(type default)
			)
			(layer "B.SilkS")
		)
		(fp_line
			(start 0.7874 -0.4064)
			(end -0.7874 -0.4064)
			(stroke
				(width 0.1524)
				(type default)
			)
			(layer "B.SilkS")
		)
		(fp_line
			(start 0.7874 0.4064)
			(end 0.7874 -0.4064)
			(stroke
				(width 0.1524)
				(type default)
			)
			(layer "B.SilkS")
		)
		(fp_line
			(start -0.67945 -0.3048)
			(end -0.67945 0.3048)
			(stroke
				(width 0.1)
				(type default)
			)
			(layer "B.Fab")
		)
		(fp_line
			(start -0.67945 0.3048)
			(end -0.120396 0.3048)
			(stroke
				(width 0.1)
				(type default)
			)
			(layer "B.Fab")
		)
		(fp_line
			(start -0.12065 -0.3048)
			(end -0.67945 -0.3048)
			(stroke
				(width 0.1)
				(type default)
			)
			(layer "B.Fab")
		)
		(fp_line
			(start -0.12065 -0.2794)
			(end -0.12065 -0.3048)
			(stroke
				(width 0.1)
				(type default)
			)
			(layer "B.Fab")
		)
		(fp_line
			(start -0.120396 0.2794)
			(end 0.12065 0.2794)
			(stroke
				(width 0.1)
				(type default)
			)
			(layer "B.Fab")
		)
		(fp_line
			(start -0.120396 0.3048)
			(end -0.120396 0.2794)
			(stroke
				(width 0.1)
				(type default)
			)
			(layer "B.Fab")
		)
		(fp_line
			(start 0.12065 -0.305054)
			(end 0.12065 -0.2794)
			(stroke
				(width 0.1)
				(type default)
			)
			(layer "B.Fab")
		)
		(fp_line
			(start 0.12065 -0.2794)
			(end -0.12065 -0.2794)
			(stroke
				(width 0.1)
				(type default)
			)
			(layer "B.Fab")
		)
		(fp_line
			(start 0.12065 0.2794)
			(end 0.12065 0.3048)
			(stroke
				(width 0.1)
				(type default)
			)
			(layer "B.Fab")
		)
		(fp_line
			(start 0.12065 0.3048)
			(end 0.67945 0.3048)
			(stroke
				(width 0.1)
				(type default)
			)
			(layer "B.Fab")
		)
		(fp_line
			(start 0.67945 -0.305054)
			(end 0.12065 -0.305054)
			(stroke
				(width 0.1)
				(type default)
			)
			(layer "B.Fab")
		)
		(fp_line
			(start 0.67945 0.3048)
			(end 0.67945 -0.305054)
			(stroke
				(width 0.1)
				(type default)
			)
			(layer "B.Fab")
		)
		(pad "1" smd circle
			(at 0.40005 0 180)
			(size 0 0)
			(layers "B.Cu" "B.Mask" "B.Paste")
			(net "PD_I3C_SPD_DDR_CPU0_OE_N")
		)
		(pad "2" smd circle
			(at -0.40005 0 180)
			(size 0 0)
			(layers "B.Cu" "B.Mask" "B.Paste")
			(net "GND")
		)
	)
	(footprint ""
		(layer "B.Cu")
		(at 40.436038 -313.866784 90)
		(property "Reference" "R2503"
			(at 0 0 90)
			(layer "B.SilkS")
			(hide yes)
			(effects
				(font
					(size 1.27 1.27)
				)
				(justify mirror)
			)
		)
		(property "Value" ""
			(at 0 0 90)
			(layer "B.Fab")
			(effects
				(font
					(size 1.27 1.27)
				)
				(justify mirror)
			)
		)
		(duplicate_pad_numbers_are_jumpers no)
		(fp_line
			(start 0.7874 -0.4064)
			(end -0.7874 -0.4064)
			(stroke
				(width 0.1524)
				(type default)
			)
			(layer "B.SilkS")
		)
		(fp_line
			(start -0.7874 -0.4064)
			(end -0.7874 0.4064)
			(stroke
				(width 0.1524)
				(type default)
			)
			(layer "B.SilkS")
		)
		(fp_line
			(start 0.7874 0.4064)
			(end 0.7874 -0.4064)
			(stroke
				(width 0.1524)
				(type default)
			)
			(layer "B.SilkS")
		)
		(fp_line
			(start -0.7874 0.4064)
			(end 0.7874 0.4064)
			(stroke
				(width 0.1524)
				(type default)
			)
			(layer "B.SilkS")
		)
		(fp_line
			(start 0.67945 -0.305054)
			(end 0.12065 -0.305054)
			(stroke
				(width 0.1)
				(type default)
			)
			(layer "B.Fab")
		)
		(fp_line
			(start 0.12065 -0.305054)
			(end 0.12065 -0.2794)
			(stroke
				(width 0.1)
				(type default)
			)
			(layer "B.Fab")
		)
		(fp_line
			(start -0.12065 -0.3048)
			(end -0.67945 -0.3048)
			(stroke
				(width 0.1)
				(type default)
			)
			(layer "B.Fab")
		)
		(fp_line
			(start -0.67945 -0.3048)
			(end -0.67945 0.3048)
			(stroke
				(width 0.1)
				(type default)
			)
			(layer "B.Fab")
		)
		(fp_line
			(start 0.12065 -0.2794)
			(end -0.12065 -0.2794)
			(stroke
				(width 0.1)
				(type default)
			)
			(layer "B.Fab")
		)
		(fp_line
			(start -0.12065 -0.2794)
			(end -0.12065 -0.3048)
			(stroke
				(width 0.1)
				(type default)
			)
			(layer "B.Fab")
		)
		(fp_line
			(start 0.12065 0.2794)
			(end 0.12065 0.3048)
			(stroke
				(width 0.1)
				(type default)
			)
			(layer "B.Fab")
		)
		(fp_line
			(start -0.120396 0.2794)
			(end 0.12065 0.2794)
			(stroke
				(width 0.1)
				(type default)
			)
			(layer "B.Fab")
		)
		(fp_line
			(start 0.67945 0.3048)
			(end 0.67945 -0.305054)
			(stroke
				(width 0.1)
				(type default)
			)
			(layer "B.Fab")
		)
		(fp_line
			(start 0.12065 0.3048)
			(end 0.67945 0.3048)
			(stroke
				(width 0.1)
				(type default)
			)
			(layer "B.Fab")
		)
		(fp_line
			(start -0.120396 0.3048)
			(end -0.120396 0.2794)
			(stroke
				(width 0.1)
				(type default)
			)
			(layer "B.Fab")
		)
		(fp_line
			(start -0.67945 0.3048)
			(end -0.120396 0.3048)
			(stroke
				(width 0.1)
				(type default)
			)
			(layer "B.Fab")
		)
		(pad "1" smd circle
			(at 0.40005 0 270)
			(size 0 0)
			(layers "B.Cu" "B.Mask" "B.Paste")
			(net "PWRGD_FAIL_CPU1_CD_R1")
		)
		(pad "2" smd circle
			(at -0.40005 0 270)
			(size 0 0)
			(layers "B.Cu" "B.Mask" "B.Paste")
			(net "PWRGD_FAIL_CPU1_CD_R")
		)
	)
	(footprint ""
		(layer "B.Cu")
		(at 184.555638 -113.37544 -90)
		(property "Reference" "C1900"
			(at 0 0 90)
			(layer "B.SilkS")
			(hide yes)
			(effects
				(font
					(size 1.27 1.27)
				)
				(justify mirror)
			)
		)
		(property "Value" ""
			(at 0 0 90)
			(layer "B.Fab")
			(effects
				(font
					(size 1.27 1.27)
				)
				(justify mirror)
			)
		)
		(duplicate_pad_numbers_are_jumpers no)
		(fp_line
			(start -0.69215 0.2921)
			(end 0.69215 0.2921)
			(stroke
				(width 0.1524)
				(type default)
			)
			(layer "B.SilkS")
		)
		(fp_line
			(start 0.69215 0.2921)
			(end 0.69215 -0.2921)
			(stroke
				(width 0.1524)
				(type default)
			)
			(layer "B.SilkS")
		)
		(fp_line
			(start -0.69215 -0.2921)
			(end -0.69215 0.2921)
			(stroke
				(width 0.1524)
				(type default)
			)
			(layer "B.SilkS")
		)
		(fp_line
			(start 0.69215 -0.2921)
			(end -0.69215 -0.2921)
			(stroke
				(width 0.1524)
				(type default)
			)
			(layer "B.SilkS")
		)
		(fp_line
			(start -0.51435 0.2794)
			(end 0.51435 0.2794)
			(stroke
				(width 0.1)
				(type default)
			)
			(layer "B.Fab")
		)
		(fp_line
			(start 0.51435 0.2794)
			(end 0.51435 -0.2794)
			(stroke
				(width 0.1)
				(type default)
			)
			(layer "B.Fab")
		)
		(fp_line
			(start -0.51435 -0.2794)
			(end -0.51435 0.2794)
			(stroke
				(width 0.1)
				(type default)
			)
			(layer "B.Fab")
		)
		(fp_line
			(start 0.51435 -0.2794)
			(end -0.51435 -0.2794)
			(stroke
				(width 0.1)
				(type default)
			)
			(layer "B.Fab")
		)
		(pad "1" smd circle
			(at 0.40005 0 90)
			(size 0 0)
			(layers "B.Cu" "B.Mask" "B.Paste")
			(net "P3V3_AUX_FPGA_VCCIO2")
		)
		(pad "2" smd circle
			(at -0.40005 0 90)
			(size 0 0)
			(layers "B.Cu" "B.Mask" "B.Paste")
			(net "GND")
		)
		(zone
			(layer "B.Cu")
			(hatch none 0.5)
			(connect_pads
				(clearance 0)
			)
			(min_thickness 0.25)
			(keepout
				(tracks not_allowed)
				(vias allowed)
				(pads allowed)
				(copperpour not_allowed)
				(footprints allowed)
			)
			(placement
				(enabled no)
				(sheetname "")
			)
			(fill
				(thermal_gap 0.5)
				(thermal_bridge_width 0.5)
				(island_removal_mode 0)
			)
			(polygon
				(pts
					(xy 184.468008 -113.18494) (xy 184.409842 -113.27638) (xy 184.409842 -113.47577) (xy 184.468008 -113.56594)
					(xy 184.643268 -113.56594) (xy 184.701688 -113.47577) (xy 184.701688 -113.27638) (xy 184.643522 -113.18494)
				)
			)
		)
	)
	(footprint ""
		(layer "B.Cu")
		(at 177.00244 -344.79992 -90)
		(property "Reference" "PC621_P1_1"
			(at 0 0 90)
			(layer "B.SilkS")
			(hide yes)
			(effects
				(font
					(size 1.27 1.27)
				)
				(justify mirror)
			)
		)
		(property "Value" ""
			(at 0 0 90)
			(layer "B.Fab")
			(effects
				(font
					(size 1.27 1.27)
				)
				(justify mirror)
			)
		)
		(duplicate_pad_numbers_are_jumpers no)
		(fp_line
			(start -0.7874 0.4064)
			(end 0.7874 0.4064)
			(stroke
				(width 0.1524)
				(type default)
			)
			(layer "B.SilkS")
		)
		(fp_line
			(start 0.7874 0.4064)
			(end 0.7874 -0.4064)
			(stroke
				(width 0.1524)
				(type default)
			)
			(layer "B.SilkS")
		)
		(fp_line
			(start -0.7874 -0.4064)
			(end -0.7874 0.4064)
			(stroke
				(width 0.1524)
				(type default)
			)
			(layer "B.SilkS")
		)
		(fp_line
			(start 0.7874 -0.4064)
			(end -0.7874 -0.4064)
			(stroke
				(width 0.1524)
				(type default)
			)
			(layer "B.SilkS")
		)
		(fp_line
			(start -0.67945 0.3048)
			(end -0.120396 0.3048)
			(stroke
				(width 0.1)
				(type default)
			)
			(layer "B.Fab")
		)
		(fp_line
			(start -0.120396 0.3048)
			(end -0.120396 0.2794)
			(stroke
				(width 0.1)
				(type default)
			)
			(layer "B.Fab")
		)
		(fp_line
			(start 0.12065 0.3048)
			(end 0.67945 0.3048)
			(stroke
				(width 0.1)
				(type default)
			)
			(layer "B.Fab")
		)
		(fp_line
			(start 0.67945 0.3048)
			(end 0.67945 -0.305054)
			(stroke
				(width 0.1)
				(type default)
			)
			(layer "B.Fab")
		)
		(fp_line
			(start -0.120396 0.2794)
			(end 0.12065 0.2794)
			(stroke
				(width 0.1)
				(type default)
			)
			(layer "B.Fab")
		)
		(fp_line
			(start 0.12065 0.2794)
			(end 0.12065 0.3048)
			(stroke
				(width 0.1)
				(type default)
			)
			(layer "B.Fab")
		)
		(fp_line
			(start -0.12065 -0.2794)
			(end -0.12065 -0.3048)
			(stroke
				(width 0.1)
				(type default)
			)
			(layer "B.Fab")
		)
		(fp_line
			(start 0.12065 -0.2794)
			(end -0.12065 -0.2794)
			(stroke
				(width 0.1)
				(type default)
			)
			(layer "B.Fab")
		)
		(fp_line
			(start -0.67945 -0.3048)
			(end -0.67945 0.3048)
			(stroke
				(width 0.1)
				(type default)
			)
			(layer "B.Fab")
		)
		(fp_line
			(start -0.12065 -0.3048)
			(end -0.67945 -0.3048)
			(stroke
				(width 0.1)
				(type default)
			)
			(layer "B.Fab")
		)
		(fp_line
			(start 0.12065 -0.305054)
			(end 0.12065 -0.2794)
			(stroke
				(width 0.1)
				(type default)
			)
			(layer "B.Fab")
		)
		(fp_line
			(start 0.67945 -0.305054)
			(end 0.12065 -0.305054)
			(stroke
				(width 0.1)
				(type default)
			)
			(layer "B.Fab")
		)
		(pad "1" smd circle
			(at 0.40005 0 90)
			(size 0 0)
			(layers "B.Cu" "B.Mask" "B.Paste")
			(net "PVCCFA_EHV_FIVRA_CPU1")
		)
		(pad "2" smd circle
			(at -0.40005 0 90)
			(size 0 0)
			(layers "B.Cu" "B.Mask" "B.Paste")
			(net "GND")
		)
	)
	(footprint ""
		(layer "B.Cu")
		(at 323.001132 -59.742324)
		(property "Reference" "R1247"
			(at 0 0 0)
			(layer "B.SilkS")
			(hide yes)
			(effects
				(font
					(size 1.27 1.27)
				)
				(justify mirror)
			)
		)
		(property "Value" ""
			(at 0 0 0)
			(layer "B.Fab")
			(effects
				(font
					(size 1.27 1.27)
				)
				(justify mirror)
			)
		)
		(duplicate_pad_numbers_are_jumpers no)
		(fp_line
			(start -0.7874 -0.4064)
			(end -0.7874 0.4064)
			(stroke
				(width 0.1524)
				(type default)
			)
			(layer "B.SilkS")
		)
		(fp_line
			(start -0.7874 0.4064)
			(end 0.7874 0.4064)
			(stroke
				(width 0.1524)
				(type default)
			)
			(layer "B.SilkS")
		)
		(fp_line
			(start 0.7874 -0.4064)
			(end -0.7874 -0.4064)
			(stroke
				(width 0.1524)
				(type default)
			)
			(layer "B.SilkS")
		)
		(fp_line
			(start 0.7874 0.4064)
			(end 0.7874 -0.4064)
			(stroke
				(width 0.1524)
				(type default)
			)
			(layer "B.SilkS")
		)
		(fp_line
			(start -0.67945 -0.3048)
			(end -0.67945 0.3048)
			(stroke
				(width 0.1)
				(type default)
			)
			(layer "B.Fab")
		)
		(fp_line
			(start -0.67945 0.3048)
			(end -0.120396 0.3048)
			(stroke
				(width 0.1)
				(type default)
			)
			(layer "B.Fab")
		)
		(fp_line
			(start -0.12065 -0.3048)
			(end -0.67945 -0.3048)
			(stroke
				(width 0.1)
				(type default)
			)
			(layer "B.Fab")
		)
		(fp_line
			(start -0.12065 -0.2794)
			(end -0.12065 -0.3048)
			(stroke
				(width 0.1)
				(type default)
			)
			(layer "B.Fab")
		)
		(fp_line
			(start -0.120396 0.2794)
			(end 0.12065 0.2794)
			(stroke
				(width 0.1)
				(type default)
			)
			(layer "B.Fab")
		)
		(fp_line
			(start -0.120396 0.3048)
			(end -0.120396 0.2794)
			(stroke
				(width 0.1)
				(type default)
			)
			(layer "B.Fab")
		)
		(fp_line
			(start 0.12065 -0.305054)
			(end 0.12065 -0.2794)
			(stroke
				(width 0.1)
				(type default)
			)
			(layer "B.Fab")
		)
		(fp_line
			(start 0.12065 -0.2794)
			(end -0.12065 -0.2794)
			(stroke
				(width 0.1)
				(type default)
			)
			(layer "B.Fab")
		)
		(fp_line
			(start 0.12065 0.2794)
			(end 0.12065 0.3048)
			(stroke
				(width 0.1)
				(type default)
			)
			(layer "B.Fab")
		)
		(fp_line
			(start 0.12065 0.3048)
			(end 0.67945 0.3048)
			(stroke
				(width 0.1)
				(type default)
			)
			(layer "B.Fab")
		)
		(fp_line
			(start 0.67945 -0.305054)
			(end 0.12065 -0.305054)
			(stroke
				(width 0.1)
				(type default)
			)
			(layer "B.Fab")
		)
		(fp_line
			(start 0.67945 0.3048)
			(end 0.67945 -0.305054)
			(stroke
				(width 0.1)
				(type default)
			)
			(layer "B.Fab")
		)
		(pad "1" smd circle
			(at 0.40005 0 180)
			(size 0 0)
			(layers "B.Cu" "B.Mask" "B.Paste")
			(net "FM_PCH_CPU_PWR_DEBUG_N")
		)
		(pad "2" smd circle
			(at -0.40005 0 180)
			(size 0 0)
			(layers "B.Cu" "B.Mask" "B.Paste")
			(net "FM_CPU_FBRK_DEBUG_N")
		)
	)
)
